(kicad_pcb
	(version 20241229)
	(generator "pcbnew")
	(generator_version "9.0")
	(general
		(thickness 1.6296)
		(legacy_teardrops no)
	)
	(paper "A3")
	(title_block
		(title "Thunderbolt to 10GbE adapter")
		(date "2026-04-21")
		(rev "1.1.0")
		(company "Antmicro Ltd")
		(comment 1 "www.antmicro.com")
		(comment 9 "footprints 1-3 of 703")
	)
	(layers
		(0 "F.Cu" signal)
		(4 "In1.Cu" signal)
		(6 "In2.Cu" signal)
		(8 "In3.Cu" signal)
		(10 "In4.Cu" signal)
		(12 "In5.Cu" signal)
		(14 "In6.Cu" signal)
		(2 "B.Cu" signal)
		(9 "F.Adhes" user "F.Adhesive")
		(11 "B.Adhes" user "B.Adhesive")
		(13 "F.Paste" user)
		(15 "B.Paste" user)
		(5 "F.SilkS" user "F.Silkscreen")
		(7 "B.SilkS" user "B.Silkscreen")
		(1 "F.Mask" user)
		(3 "B.Mask" user)
		(17 "Dwgs.User" user "User.Drawings")
		(19 "Cmts.User" user "User.Comments")
		(21 "Eco1.User" user "User.Eco1")
		(23 "Eco2.User" user "User.Eco2")
		(25 "Edge.Cuts" user)
		(27 "Margin" user)
		(31 "F.CrtYd" user "F.Courtyard")
		(29 "B.CrtYd" user "B.Courtyard")
		(35 "F.Fab" user)
		(33 "B.Fab" user)
	)
	(footprint "antmicro-footprints:R_0402_1005Metric"
		(layer "F.Cu")
		(at 173.105 79.341)
		(descr "Resistor SMD 0402")
		(tags "resistor SMD 0402")
		(property "Reference" "R173"
			(at -1.105 1.659 0)
			(layer "F.SilkS")
			(effects
				(font
					(size 0.7 0.7)
					(thickness 0.15)
				)
				(justify left bottom)
			)
		)
		(property "Value" "R_2k_0402"
			(at -1.011843 1.772047 0)
			(layer "F.Fab")
			(effects
				(font
					(size 0.7 0.7)
					(thickness 0.15)
				)
				(justify left bottom)
			)
		)
		(property "Datasheet" "https://www.bourns.com/docs/product-datasheets/cr.pdf"
			(at 0 0 0)
			(layer "F.Fab")
			(hide yes)
			(effects
				(font
					(size 1.27 1.27)
					(thickness 0.15)
				)
			)
		)
		(property "Description" "SMD Chip Resistor, 2 kohm, ± 1%, 62.5 mW, 0402 [1005 Metric], Thick Film, General Purpose"
			(at 0 0 0)
			(layer "F.Fab")
			(hide yes)
			(effects
				(font
					(size 1.27 1.27)
					(thickness 0.15)
				)
			)
		)
		(property "MPN" "CR0402-FX-2001GLF"
			(at 0 0 0)
			(unlocked yes)
			(layer "F.Fab")
			(hide yes)
			(effects
				(font
					(size 1 1)
					(thickness 0.15)
				)
			)
		)
		(property "Manufacturer" "Bourns"
			(at 0 0 0)
			(unlocked yes)
			(layer "F.Fab")
			(hide yes)
			(effects
				(font
					(size 1 1)
					(thickness 0.15)
				)
			)
		)
		(property "License" "Apache-2.0"
			(at 0 0 0)
			(unlocked yes)
			(layer "F.Fab")
			(hide yes)
			(effects
				(font
					(size 1 1)
					(thickness 0.15)
				)
			)
		)
		(property "Author" "Antmicro"
			(at 0 0 0)
			(unlocked yes)
			(layer "F.Fab")
			(hide yes)
			(effects
				(font
					(size 1 1)
					(thickness 0.15)
				)
			)
		)
		(property "Val" "2k"
			(at 0 0 0)
			(unlocked yes)
			(layer "F.Fab")
			(hide yes)
			(effects
				(font
					(size 1 1)
					(thickness 0.15)
				)
			)
		)
		(property "Tolerance" "1%"
			(at 0 0 0)
			(unlocked yes)
			(layer "F.Fab")
			(hide yes)
			(effects
				(font
					(size 1 1)
					(thickness 0.15)
				)
			)
		)
		(sheetname "/X710-AT2 Misc/")
		(sheetfile "x710-at2-mics.kicad_sch")
		(attr smd)
		(fp_rect
			(start -0.925 -0.47)
			(end 0.925 0.47)
			(stroke
				(width 0.05)
				(type default)
			)
			(fill no)
			(layer "F.CrtYd")
		)
		(fp_rect
			(start -0.5 -0.25)
			(end 0.5 0.25)
			(stroke
				(width 0.15)
				(type solid)
			)
			(fill no)
			(layer "F.Fab")
		)
		(fp_text user "${REFERENCE}"
			(at -0.95 3.168 0)
			(layer "F.Fab")
			(effects
				(font
					(size 0.7 0.7)
					(thickness 0.15)
				)
				(justify left bottom)
			)
		)
		(fp_text user "Author: Antmicro"
			(at -0.95 4.169 0)
			(layer "F.Fab")
			(effects
				(font
					(size 0.7 0.7)
					(thickness 0.15)
				)
				(justify left bottom)
			)
		)
		(fp_text user "License: Apache-2.0"
			(at -0.95 5.169 0)
			(layer "F.Fab")
			(effects
				(font
					(size 0.7 0.7)
					(thickness 0.15)
				)
				(justify left bottom)
			)
		)
		(pad "1" smd roundrect
			(at -0.48 0)
			(size 0.59 0.64)
			(layers "F.Cu" "F.Mask" "F.Paste")
			(roundrect_rratio 0.25)
			(net 148 "/X710-AT2 Misc/MDIO.MDC")
			(pintype "passive")
		)
		(pad "2" smd roundrect
			(at 0.48 0)
			(size 0.59 0.64)
			(layers "F.Cu" "F.Mask" "F.Paste")
			(roundrect_rratio 0.25)
			(net 18 "+1V88")
			(pintype "passive")
		)
	)
	(footprint "antmicro-footprints:C_Pol_EIA-B"
		(layer "F.Cu")
		(at 137.75 57.5 90)
		(property "Reference" "C325"
			(at 2.7 1.85 90)
			(layer "F.SilkS")
			(effects
				(font
					(size 0.7 0.7)
					(thickness 0.15)
				)
				(justify left bottom)
			)
		)
		(property "Value" "C_Pol_330u_6.3V_KEMET-T520-B"
			(at 0 2.85 90)
			(layer "F.Fab")
			(effects
				(font
					(size 0.7 0.7)
					(thickness 0.15)
				)
				(justify left bottom)
			)
		)
		(property "Datasheet" "https://www.kemet.com/en/us/capacitors/product/T520B337M006ATE040.html"
			(at 0 0 90)
			(layer "F.Fab")
			(hide yes)
			(effects
				(font
					(size 1.27 1.27)
					(thickness 0.15)
				)
			)
		)
		(property "Description" "Tantalum Polymer Capacitor, KO-CAP®, 330 µF, ± 20%, 6.3 V, B, 0.04 ohm, 1411 [3528 Metric]"
			(at 0 0 90)
			(layer "F.Fab")
			(hide yes)
			(effects
				(font
					(size 1.27 1.27)
					(thickness 0.15)
				)
			)
		)
		(property "Val" "330u"
			(at 0 0 90)
			(unlocked yes)
			(layer "F.Fab")
			(hide yes)
			(effects
				(font
					(size 1 1)
					(thickness 0.15)
				)
			)
		)
		(property "MPN" "T520B337M006ATE040"
			(at 0 0 90)
			(unlocked yes)
			(layer "F.Fab")
			(hide yes)
			(effects
				(font
					(size 1 1)
					(thickness 0.15)
				)
			)
		)
		(property "Manufacturer" "KEMET"
			(at 0 0 90)
			(unlocked yes)
			(layer "F.Fab")
			(hide yes)
			(effects
				(font
					(size 1 1)
					(thickness 0.15)
				)
			)
		)
		(property "License" "Apache-2.0"
			(at 0 0 90)
			(unlocked yes)
			(layer "F.Fab")
			(hide yes)
			(effects
				(font
					(size 1 1)
					(thickness 0.15)
				)
			)
		)
		(property "Author" "Antmicro"
			(at 0 0 90)
			(unlocked yes)
			(layer "F.Fab")
			(hide yes)
			(effects
				(font
					(size 1 1)
					(thickness 0.15)
				)
			)
		)
		(property "Voltage" "6.3V"
			(at 0 0 90)
			(unlocked yes)
			(layer "F.Fab")
			(hide yes)
			(effects
				(font
					(size 1 1)
					(thickness 0.15)
				)
			)
		)
		(property "Dielectric" "template_dielectric"
			(at 0 0 90)
			(unlocked yes)
			(layer "F.Fab")
			(hide yes)
			(effects
				(font
					(size 1 1)
					(thickness 0.15)
				)
			)
		)
		(sheetname "/Power input/")
		(sheetfile "power_input.kicad_sch")
		(attr smd dnp)
		(fp_line
			(start -2.521 -1.676)
			(end -2.123 -1.676)
			(stroke
				(width 0.15)
				(type solid)
			)
			(layer "F.SilkS")
		)
		(fp_line
			(start -1.8 -1.6)
			(end 1.8 -1.6)
			(stroke
				(width 0.15)
				(type solid)
			)
			(layer "F.SilkS")
		)
		(fp_line
			(start -2.325 -1.475)
			(end -2.325 -1.878)
			(stroke
				(width 0.15)
				(type solid)
			)
			(layer "F.SilkS")
		)
		(fp_line
			(start 1.8 -1.3)
			(end 1.8 -1.6)
			(stroke
				(width 0.15)
				(type solid)
			)
			(layer "F.SilkS")
		)
		(fp_line
			(start -1.8 -1.3)
			(end -1.8 -1.6)
			(stroke
				(width 0.15)
				(type solid)
			)
			(layer "F.SilkS")
		)
		(fp_line
			(start 1.8 1.3)
			(end 1.8 1.6)
			(stroke
				(width 0.15)
				(type solid)
			)
			(layer "F.SilkS")
		)
		(fp_line
			(start -1.8 1.3)
			(end -1.8 1.6)
			(stroke
				(width 0.15)
				(type solid)
			)
			(layer "F.SilkS")
		)
		(fp_line
			(start 1.8 1.6)
			(end -1.8 1.6)
			(stroke
				(width 0.15)
				(type solid)
			)
			(layer "F.SilkS")
		)
		(fp_line
			(start 1.959 -1.75)
			(end -1.97 -1.75)
			(stroke
				(width 0.05)
				(type solid)
			)
			(layer "F.CrtYd")
		)
		(fp_line
			(start 1.959 -1.75)
			(end 1.959 -1.35)
			(stroke
				(width 0.05)
				(type solid)
			)
			(layer "F.CrtYd")
		)
		(fp_line
			(start -1.97 -1.75)
			(end -1.97 -1.35)
			(stroke
				(width 0.05)
				(type solid)
			)
			(layer "F.CrtYd")
		)
		(fp_line
			(start 2.399 -1.35)
			(end 1.959 -1.35)
			(stroke
				(width 0.05)
				(type solid)
			)
			(layer "F.CrtYd")
		)
		(fp_line
			(start 2.399 -1.35)
			(end 2.4 1.35)
			(stroke
				(width 0.05)
				(type solid)
			)
			(layer "F.CrtYd")
		)
		(fp_line
			(start -1.97 -1.35)
			(end -2.41 -1.35)
			(stroke
				(width 0.05)
				(type solid)
			)
			(layer "F.CrtYd")
		)
		(fp_line
			(start -2.411 -1.35)
			(end -2.41 1.35)
			(stroke
				(width 0.05)
				(type solid)
			)
			(layer "F.CrtYd")
		)
		(fp_line
			(start 2.4 1.35)
			(end 1.96 1.35)
			(stroke
				(width 0.05)
				(type solid)
			)
			(layer "F.CrtYd")
		)
		(fp_line
			(start 1.96 1.35)
			(end 1.96 1.75)
			(stroke
				(width 0.05)
				(type solid)
			)
			(layer "F.CrtYd")
		)
		(fp_line
			(start -1.97 1.35)
			(end -2.41 1.35)
			(stroke
				(width 0.05)
				(type solid)
			)
			(layer "F.CrtYd")
		)
		(fp_line
			(start -1.97 1.35)
			(end -1.97 1.75)
			(stroke
				(width 0.05)
				(type solid)
			)
			(layer "F.CrtYd")
		)
		(fp_line
			(start 1.96 1.75)
			(end -1.97 1.75)
			(stroke
				(width 0.05)
				(type solid)
			)
			(layer "F.CrtYd")
		)
		(fp_line
			(start -1.7 1.324)
			(end -1.551 1.475)
			(stroke
				(width 0.15)
				(type solid)
			)
			(layer "F.Fab")
		)
		(fp_rect
			(start -1.72 -1.5)
			(end 1.719 1.499)
			(stroke
				(width 0.15)
				(type solid)
			)
			(fill no)
			(layer "F.Fab")
		)
		(fp_text user "License: Apache-2.0"
			(at -2.665 5.65 90)
			(layer "F.Fab")
			(effects
				(font
					(size 0.7 0.7)
					(thickness 0.15)
				)
				(justify left bottom)
			)
		)
		(fp_text user "${REFERENCE}"
			(at -2.665 4.45 90)
			(layer "F.Fab")
			(effects
				(font
					(size 0.7 0.7)
					(thickness 0.15)
				)
				(justify left bottom)
			)
		)
		(fp_text user "Author: Antmicro"
			(at -2.665 6.85 90)
			(layer "F.Fab")
			(effects
				(font
					(size 0.7 0.7)
					(thickness 0.15)
				)
				(justify left bottom)
			)
		)
		(pad "1" smd roundrect
			(at -1.551 0 90)
			(size 1.2 2.2)
			(layers "F.Cu" "F.Mask" "F.Paste")
			(roundrect_rratio 0.1)
			(net 40 "+5V")
			(pintype "passive")
		)
		(pad "2" smd roundrect
			(at 1.55 0 90)
			(size 1.2 2.2)
			(layers "F.Cu" "F.Mask" "F.Paste")
			(roundrect_rratio 0.1)
			(net 23 "GND")
			(pintype "passive")
		)
	)
	(footprint "antmicro-footprints:R_0402_1005Metric"
		(layer "F.Cu")
		(at 119.25 66.5 180)
		(descr "Resistor SMD 0402")
		(tags "resistor SMD 0402")
		(property "Reference" "R134"
			(at -3.45 -1.4 180)
			(layer "F.SilkS")
			(effects
				(font
					(size 0.7 0.7)
					(thickness 0.15)
				)
				(justify left bottom)
			)
		)
		(property "Value" "R_10k_0402"
			(at -1.011843 1.772047 180)
			(layer "F.Fab")
			(effects
				(font
					(size 0.7 0.7)
					(thickness 0.15)
				)
				(justify left bottom)
			)
		)
		(property "Datasheet" "https://www.bourns.com/docs/product-datasheets/cr.pdf"
			(at 0 0 180)
			(layer "F.Fab")
			(hide yes)
			(effects
				(font
					(size 1.27 1.27)
					(thickness 0.15)
				)
			)
		)
		(property "Description" "SMD Chip Resistor, 10 kohm, ± 1%, 62.5 mW, 0402 [1005 Metric], Thick Film, General Purpose"
			(at 0 0 180)
			(layer "F.Fab")
			(hide yes)
			(effects
				(font
					(size 1.27 1.27)
					(thickness 0.15)
				)
			)
		)
		(property "MPN" "CR0402-FX-1002GLF"
			(at 0 0 180)
			(unlocked yes)
			(layer "F.Fab")
			(hide yes)
			(effects
				(font
					(size 1 1)
					(thickness 0.15)
				)
			)
		)
		(property "Manufacturer" "Bourns"
			(at 0 0 180)
			(unlocked yes)
			(layer "F.Fab")
			(hide yes)
			(effects
				(font
					(size 1 1)
					(thickness 0.15)
				)
			)
		)
		(property "License" "Apache-2.0"
			(at 0 0 180)
			(unlocked yes)
			(layer "F.Fab")
			(hide yes)
			(effects
				(font
					(size 1 1)
					(thickness 0.15)
				)
			)
		)
		(property "Author" "Antmicro"
			(at 0 0 180)
			(unlocked yes)
			(layer "F.Fab")
			(hide yes)
			(effects
				(font
					(size 1 1)
					(thickness 0.15)
				)
			)
		)
		(property "Val" "10k"
			(at 0 0 180)
			(unlocked yes)
			(layer "F.Fab")
			(hide yes)
			(effects
				(font
					(size 1 1)
					(thickness 0.15)
				)
			)
		)
		(property "Tolerance" "1%"
			(at 0 0 180)
			(unlocked yes)
			(layer "F.Fab")
			(hide yes)
			(effects
				(font
					(size 1 1)
					(thickness 0.15)
				)
			)
		)
		(sheetname "/X710-AT2 RSVD/")
		(sheetfile "x710-at2-rsvd.kicad_sch")
		(attr smd)
		(fp_rect
			(start -0.925 -0.47)
			(end 0.925 0.47)
			(stroke
				(width 0.05)
				(type default)
			)
			(fill no)
			(layer "F.CrtYd")
		)
		(fp_rect
			(start -0.5 -0.25)
			(end 0.5 0.25)
			(stroke
				(width 0.15)
				(type solid)
			)
			(fill no)
			(layer "F.Fab")
		)
		(fp_text user "${REFERENCE}"
			(at -0.95 3.168 180)
			(layer "F.Fab")
			(effects
				(font
					(size 0.7 0.7)
					(thickness 0.15)
				)
				(justify left bottom)
			)
		)
		(fp_text user "Author: Antmicro"
			(at -0.95 4.169 180)
			(layer "F.Fab")
			(effects
				(font
					(size 0.7 0.7)
					(thickness 0.15)
				)
				(justify left bottom)
			)
		)
		(fp_text user "License: Apache-2.0"
			(at -0.95 5.169 180)
			(layer "F.Fab")
			(effects
				(font
					(size 0.7 0.7)
					(thickness 0.15)
				)
				(justify left bottom)
			)
		)
		(pad "1" smd roundrect
			(at -0.48 0 180)
			(size 0.59 0.64)
			(layers "F.Cu" "F.Mask" "F.Paste")
			(roundrect_rratio 0.25)
			(net 23 "GND")
			(pintype "passive")
		)
		(pad "2" smd roundrect
			(at 0.48 0 180)
			(size 0.59 0.64)
			(layers "F.Cu" "F.Mask" "F.Paste")
			(roundrect_rratio 0.25)
			(net 90 "/X710-AT2 RSVD/DEBUG_W7")
			(pintype "passive")
		)
	)
)
